(kicad_pcb
	(version 20260206)
	(generator "pcbnew")
	(generator_version "10.0")
	(general
		(thickness 1.6)
		(legacy_teardrops no)
	)
	(paper "A4")
	(title_block
		(title "pdpb — Lightning_PDPB_BRD.brd")
		(comment 1 "Lightning (Wiwynn / Facebook NVMe JBOF) / footprints 924-929 of 1140")
	)
	(layers
		(0 "F.Cu" signal "TOP")
		(4 "In1.Cu" signal "L2GND")
		(6 "In2.Cu" signal "L3")
		(8 "In3.Cu" signal "L4VCC")
		(10 "In4.Cu" signal "L5VCC")
		(12 "In5.Cu" signal "L6")
		(14 "In6.Cu" signal "L7GND")
		(2 "B.Cu" signal "BOTTOM")
		(9 "F.Adhes" user "F.Adhesive")
		(11 "B.Adhes" user "B.Adhesive")
		(13 "F.Paste" user "Package Geometry/Pastemask Top")
		(15 "B.Paste" user "Package Geometry/Pastemask Bottom")
		(5 "F.SilkS" user "Ref Des/Silkscreen Top")
		(7 "B.SilkS" user "Ref Des/Silkscreen Bottom")
		(1 "F.Mask" user "Board Geometry/Soldermask Top")
		(3 "B.Mask" user "Board Geometry/Soldermask Bottom")
		(17 "Dwgs.User" user "User.Drawings")
		(19 "Cmts.User" user "User.Comments")
		(21 "Eco1.User" user "User.Eco1")
		(23 "Eco2.User" user "User.Eco2")
		(25 "Edge.Cuts" user "Board Geometry/Outline")
		(27 "Margin" user)
		(31 "F.CrtYd" user "Package Geometry/Place Bound Top")
		(29 "B.CrtYd" user "Package Geometry/Place Bound Bottom")
		(35 "F.Fab" user "Ref Des/Assembly Top")
		(33 "B.Fab" user "Ref Des/Assembly Bottom")
	)
	(footprint ""
		(layer "F.Cu")
		(at 215.7984 -494.0808 90)
		(property "Reference" "SR1091"
			(at 0 0 90)
			(layer "F.SilkS")
			(hide yes)
			(effects
				(font
					(size 1.27 1.27)
				)
			)
		)
		(property "Value" "4K7R2F-GP"
			(at 0.064008 -3.993896 90)
			(unlocked yes)
			(layer "F.Fab")
			(hide yes)
			(effects
				(font
					(size 1.016 1.016)
					(thickness 0.1524)
				)
			)
		)
		(property "Device Type" "R402H16"
			(at 0.064008 -5.517896 90)
			(unlocked yes)
			(layer "F.Fab")
			(hide yes)
			(effects
				(font
					(size 1.016 1.016)
					(thickness 0.1524)
				)
			)
		)
		(duplicate_pad_numbers_are_jumpers no)
		(fp_line
			(start 0.508 -0.9398)
			(end -0.508 -0.9398)
			(stroke
				(width 0.1524)
				(type default)
			)
			(layer "F.SilkS")
		)
		(fp_line
			(start -0.508 -0.9398)
			(end -0.508 0.9398)
			(stroke
				(width 0.1524)
				(type default)
			)
			(layer "F.SilkS")
		)
		(fp_rect
			(start -0.508 0.9398)
			(end 0.508 -0.9398)
			(stroke
				(width 0)
				(type default)
			)
			(fill no)
			(layer "F.CrtYd")
		)
		(fp_rect
			(start -0.508 0.9398)
			(end 0.508 -0.9398)
			(stroke
				(width 0)
				(type default)
			)
			(fill no)
			(layer "F.Fab")
		)
		(pad "1" smd custom
			(at 0 -0.4445 90)
			(size 0.1397 0.1397)
			(layers "F.Cu" "F.Mask" "F.Paste")
			(net "P3V3")
			(options
				(clearance outline)
				(anchor circle)
			)
			(primitives
				(gr_poly
					(pts
						(arc
							(start -0.1778 -0.2794)
							(mid -0.249642 -0.249642)
							(end -0.2794 -0.1778)
						)
						(arc
							(start -0.2794 0.1778)
							(mid -0.249642 0.249642)
							(end -0.1778 0.2794)
						)
						(arc
							(start 0.1778 0.2794)
							(mid 0.249642 0.249642)
							(end 0.2794 0.1778)
						)
						(arc
							(start 0.2794 -0.1778)
							(mid 0.249642 -0.249642)
							(end 0.1778 -0.2794)
						)
					)
					(width 0)
					(fill yes)
				)
			)
		)
		(pad "2" smd custom
			(at 0 0.4445 90)
			(size 0.1397 0.1397)
			(layers "F.Cu" "F.Mask" "F.Paste")
			(net "DUALPORTEN#0")
			(options
				(clearance outline)
				(anchor circle)
			)
			(primitives
				(gr_poly
					(pts
						(arc
							(start -0.1778 -0.2794)
							(mid -0.249642 -0.249642)
							(end -0.2794 -0.1778)
						)
						(arc
							(start -0.2794 0.1778)
							(mid -0.249642 0.249642)
							(end -0.1778 0.2794)
						)
						(arc
							(start 0.1778 0.2794)
							(mid 0.249642 0.249642)
							(end 0.2794 0.1778)
						)
						(arc
							(start 0.2794 -0.1778)
							(mid 0.249642 -0.249642)
							(end 0.1778 -0.2794)
						)
					)
					(width 0)
					(fill yes)
				)
			)
		)
	)
	(footprint ""
		(layer "F.Cu")
		(at 17.018 -267.843)
		(property "Reference" "Q88"
			(at 0 0 0)
			(layer "F.SilkS")
			(hide yes)
			(effects
				(font
					(size 1.27 1.27)
				)
			)
		)
		(property "Value" "2N7002A-7-GP"
			(at 0.127 -8.9662 0)
			(unlocked yes)
			(layer "F.Fab")
			(hide yes)
			(effects
				(font
					(size 1.016 1.016)
					(thickness 0.1524)
				)
			)
		)
		(property "Device Type" "SOT23DGS2D4H48"
			(at 0.127 -10.4902 0)
			(unlocked yes)
			(layer "F.Fab")
			(hide yes)
			(effects
				(font
					(size 1.016 1.016)
					(thickness 0.1524)
				)
			)
		)
		(duplicate_pad_numbers_are_jumpers no)
		(fp_line
			(start -1.651 -1.778)
			(end -1.651 1.778)
			(stroke
				(width 0.1524)
				(type default)
			)
			(layer "F.SilkS")
		)
		(fp_line
			(start -1.651 1.778)
			(end 1.651 1.778)
			(stroke
				(width 0.1524)
				(type default)
			)
			(layer "F.SilkS")
		)
		(fp_line
			(start 1.651 -1.778)
			(end -1.651 -1.778)
			(stroke
				(width 0.1524)
				(type default)
			)
			(layer "F.SilkS")
		)
		(fp_line
			(start 1.651 1.778)
			(end 1.651 -1.778)
			(stroke
				(width 0.1524)
				(type default)
			)
			(layer "F.SilkS")
		)
		(fp_poly
			(pts
				(xy -1.778 1.8796) (xy -1.778 -1.8796) (xy 1.778 -1.8796) (xy 1.778 1.8796)
			)
			(stroke
				(width 0)
				(type default)
			)
			(fill no)
			(layer "F.CrtYd")
		)
		(fp_poly
			(pts
				(xy -1.778 1.8796) (xy -1.778 -1.8796) (xy 1.778 -1.8796) (xy 1.778 1.8796)
			)
			(stroke
				(width 0)
				(type default)
			)
			(fill no)
			(layer "F.Fab")
		)
		(pad "D" smd custom
			(at 0 -0.9525)
			(size 0.1905 0.1905)
			(layers "F.Cu" "F.Mask" "F.Paste")
			(net "SSD_ACT_DR12_MOS_N")
			(options
				(clearance outline)
				(anchor circle)
			)
			(primitives
				(gr_poly
					(pts
						(arc
							(start -0.1778 0.5715)
							(mid -0.321484 0.511984)
							(end -0.381 0.3683)
						)
						(arc
							(start -0.381 -0.3683)
							(mid -0.321484 -0.511984)
							(end -0.1778 -0.5715)
						)
						(arc
							(start 0.1778 -0.5715)
							(mid 0.321484 -0.511984)
							(end 0.381 -0.3683)
						)
						(arc
							(start 0.381 0.3683)
							(mid 0.321484 0.511984)
							(end 0.1778 0.5715)
						)
					)
					(width 0)
					(fill yes)
				)
			)
		)
		(pad "G" smd custom
			(at -0.98425 0.9525)
			(size 0.1905 0.1905)
			(layers "F.Cu" "F.Mask" "F.Paste")
			(net "ATTN_LED_DR12_AND_R")
			(options
				(clearance outline)
				(anchor circle)
			)
			(primitives
				(gr_poly
					(pts
						(arc
							(start -0.1778 0.5715)
							(mid -0.321484 0.511984)
							(end -0.381 0.3683)
						)
						(arc
							(start -0.381 -0.3683)
							(mid -0.321484 -0.511984)
							(end -0.1778 -0.5715)
						)
						(arc
							(start 0.1778 -0.5715)
							(mid 0.321484 -0.511984)
							(end 0.381 -0.3683)
						)
						(arc
							(start 0.381 0.3683)
							(mid 0.321484 0.511984)
							(end 0.1778 0.5715)
						)
					)
					(width 0)
					(fill yes)
				)
			)
		)
		(pad "S" smd custom
			(at 0.98425 0.9525)
			(size 0.1905 0.1905)
			(layers "F.Cu" "F.Mask" "F.Paste")
			(net "SSD_ACT_DR12_R")
			(options
				(clearance outline)
				(anchor circle)
			)
			(primitives
				(gr_poly
					(pts
						(arc
							(start -0.1778 0.5715)
							(mid -0.321484 0.511984)
							(end -0.381 0.3683)
						)
						(arc
							(start -0.381 -0.3683)
							(mid -0.321484 -0.511984)
							(end -0.1778 -0.5715)
						)
						(arc
							(start 0.1778 -0.5715)
							(mid 0.321484 -0.511984)
							(end 0.381 -0.3683)
						)
						(arc
							(start 0.381 0.3683)
							(mid 0.321484 0.511984)
							(end 0.1778 0.5715)
						)
					)
					(width 0)
					(fill yes)
				)
			)
		)
	)
	(footprint ""
		(layer "F.Cu")
		(at 43.434 -7.0104 90)
		(property "Reference" "Q96"
			(at 0 0 90)
			(layer "F.SilkS")
			(hide yes)
			(effects
				(font
					(size 1.27 1.27)
				)
			)
		)
		(property "Value" "2N7002A-7-GP"
			(at 0.127 -8.9662 90)
			(unlocked yes)
			(layer "F.Fab")
			(hide yes)
			(effects
				(font
					(size 1.016 1.016)
					(thickness 0.1524)
				)
			)
		)
		(property "Device Type" "SOT23DGS2D4H48"
			(at 0.127 -10.4902 90)
			(unlocked yes)
			(layer "F.Fab")
			(hide yes)
			(effects
				(font
					(size 1.016 1.016)
					(thickness 0.1524)
				)
			)
		)
		(duplicate_pad_numbers_are_jumpers no)
		(fp_line
			(start 1.651 -1.778)
			(end -1.651 -1.778)
			(stroke
				(width 0.1524)
				(type default)
			)
			(layer "F.SilkS")
		)
		(fp_line
			(start -1.651 -1.778)
			(end -1.651 1.778)
			(stroke
				(width 0.1524)
				(type default)
			)
			(layer "F.SilkS")
		)
		(fp_line
			(start 1.651 1.778)
			(end 1.651 -1.778)
			(stroke
				(width 0.1524)
				(type default)
			)
			(layer "F.SilkS")
		)
		(fp_line
			(start -1.651 1.778)
			(end 1.651 1.778)
			(stroke
				(width 0.1524)
				(type default)
			)
			(layer "F.SilkS")
		)
		(fp_poly
			(pts
				(xy -1.778 1.8796) (xy -1.778 -1.8796) (xy 1.778 -1.8796) (xy 1.778 1.8796)
			)
			(stroke
				(width 0)
				(type default)
			)
			(fill no)
			(layer "F.CrtYd")
		)
		(fp_poly
			(pts
				(xy -1.778 1.8796) (xy -1.778 -1.8796) (xy 1.778 -1.8796) (xy 1.778 1.8796)
			)
			(stroke
				(width 0)
				(type default)
			)
			(fill no)
			(layer "F.Fab")
		)
		(pad "D" smd custom
			(at 0 -0.9525 90)
			(size 0.1905 0.1905)
			(layers "F.Cu" "F.Mask" "F.Paste")
			(net "P12V_MOST14_GATE_D")
			(options
				(clearance outline)
				(anchor circle)
			)
			(primitives
				(gr_poly
					(pts
						(arc
							(start -0.1778 0.5715)
							(mid -0.321484 0.511984)
							(end -0.381 0.3683)
						)
						(arc
							(start -0.381 -0.3683)
							(mid -0.321484 -0.511984)
							(end -0.1778 -0.5715)
						)
						(arc
							(start 0.1778 -0.5715)
							(mid 0.321484 -0.511984)
							(end 0.381 -0.3683)
						)
						(arc
							(start 0.381 0.3683)
							(mid 0.321484 0.511984)
							(end 0.1778 0.5715)
						)
					)
					(width 0)
					(fill yes)
				)
			)
		)
		(pad "G" smd custom
			(at -0.98425 0.9525 90)
			(size 0.1905 0.1905)
			(layers "F.Cu" "F.Mask" "F.Paste")
			(net "P12V_MOST14_GATE")
			(options
				(clearance outline)
				(anchor circle)
			)
			(primitives
				(gr_poly
					(pts
						(arc
							(start -0.1778 0.5715)
							(mid -0.321484 0.511984)
							(end -0.381 0.3683)
						)
						(arc
							(start -0.381 -0.3683)
							(mid -0.321484 -0.511984)
							(end -0.1778 -0.5715)
						)
						(arc
							(start 0.1778 -0.5715)
							(mid 0.321484 -0.511984)
							(end 0.381 -0.3683)
						)
						(arc
							(start 0.381 0.3683)
							(mid 0.321484 0.511984)
							(end 0.1778 0.5715)
						)
					)
					(width 0)
					(fill yes)
				)
			)
		)
		(pad "S" smd custom
			(at 0.98425 0.9525 90)
			(size 0.1905 0.1905)
			(layers "F.Cu" "F.Mask" "F.Paste")
			(net "GND")
			(options
				(clearance outline)
				(anchor circle)
			)
			(primitives
				(gr_poly
					(pts
						(arc
							(start -0.1778 0.5715)
							(mid -0.321484 0.511984)
							(end -0.381 0.3683)
						)
						(arc
							(start -0.381 -0.3683)
							(mid -0.321484 -0.511984)
							(end -0.1778 -0.5715)
						)
						(arc
							(start 0.1778 -0.5715)
							(mid 0.321484 -0.511984)
							(end 0.381 -0.3683)
						)
						(arc
							(start 0.381 0.3683)
							(mid 0.321484 0.511984)
							(end 0.1778 0.5715)
						)
					)
					(width 0)
					(fill yes)
				)
			)
		)
	)
	(footprint ""
		(layer "F.Cu")
		(at 32.131 -390.525 -90)
		(property "Reference" "R399"
			(at 0 0 270)
			(layer "F.SilkS")
			(hide yes)
			(effects
				(font
					(size 1.27 1.27)
				)
			)
		)
		(property "Value" "0R2J-2-GP"
			(at 0.064008 -3.993896 270)
			(unlocked yes)
			(layer "F.Fab")
			(hide yes)
			(effects
				(font
					(size 1.016 1.016)
					(thickness 0.1524)
				)
			)
		)
		(property "Device Type" "R402H16"
			(at 0.064008 -5.517896 270)
			(unlocked yes)
			(layer "F.Fab")
			(hide yes)
			(effects
				(font
					(size 1.016 1.016)
					(thickness 0.1524)
				)
			)
		)
		(duplicate_pad_numbers_are_jumpers no)
		(fp_line
			(start -0.508 -0.9398)
			(end -0.508 0.9398)
			(stroke
				(width 0.1524)
				(type default)
			)
			(layer "F.SilkS")
		)
		(fp_line
			(start 0.508 -0.9398)
			(end -0.508 -0.9398)
			(stroke
				(width 0.1524)
				(type default)
			)
			(layer "F.SilkS")
		)
		(fp_rect
			(start -0.508 0.9398)
			(end 0.508 -0.9398)
			(stroke
				(width 0)
				(type default)
			)
			(fill no)
			(layer "F.CrtYd")
		)
		(fp_rect
			(start -0.508 0.9398)
			(end 0.508 -0.9398)
			(stroke
				(width 0)
				(type default)
			)
			(fill no)
			(layer "F.Fab")
		)
		(pad "1" smd custom
			(at 0 -0.4445 270)
			(size 0.1397 0.1397)
			(layers "F.Cu" "F.Mask" "F.Paste")
			(net "SCL_DR6_R")
			(options
				(clearance outline)
				(anchor circle)
			)
			(primitives
				(gr_poly
					(pts
						(arc
							(start -0.1778 -0.2794)
							(mid -0.249642 -0.249642)
							(end -0.2794 -0.1778)
						)
						(arc
							(start -0.2794 0.1778)
							(mid -0.249642 0.249642)
							(end -0.1778 0.2794)
						)
						(arc
							(start 0.1778 0.2794)
							(mid 0.249642 0.249642)
							(end 0.2794 0.1778)
						)
						(arc
							(start 0.2794 -0.1778)
							(mid 0.249642 -0.249642)
							(end 0.1778 -0.2794)
						)
					)
					(width 0)
					(fill yes)
				)
			)
		)
		(pad "2" smd custom
			(at 0 0.4445 270)
			(size 0.1397 0.1397)
			(layers "F.Cu" "F.Mask" "F.Paste")
			(net "SCL_DR6")
			(options
				(clearance outline)
				(anchor circle)
			)
			(primitives
				(gr_poly
					(pts
						(arc
							(start -0.1778 -0.2794)
							(mid -0.249642 -0.249642)
							(end -0.2794 -0.1778)
						)
						(arc
							(start -0.2794 0.1778)
							(mid -0.249642 0.249642)
							(end -0.1778 0.2794)
						)
						(arc
							(start 0.1778 0.2794)
							(mid 0.249642 0.249642)
							(end 0.2794 0.1778)
						)
						(arc
							(start 0.2794 -0.1778)
							(mid 0.249642 -0.249642)
							(end 0.1778 -0.2794)
						)
					)
					(width 0)
					(fill yes)
				)
			)
		)
	)
	(footprint ""
		(layer "F.Cu")
		(at 87.122 -106.299)
		(property "Reference" "C8931"
			(at 0 0 0)
			(layer "F.SilkS")
			(hide yes)
			(effects
				(font
					(size 1.27 1.27)
				)
			)
		)
		(property "Value" "SC1U10V2KX-7-GP"
			(at 1.1811 -2.7051 0)
			(unlocked yes)
			(layer "F.Fab")
			(hide yes)
			(effects
				(font
					(size 1.016 1.016)
					(thickness 0.1524)
				)
			)
		)
		(property "Device Type" "C402H22"
			(at 1.1811 -4.2291 0)
			(unlocked yes)
			(layer "F.Fab")
			(hide yes)
			(effects
				(font
					(size 1.016 1.016)
					(thickness 0.1524)
				)
			)
		)
		(duplicate_pad_numbers_are_jumpers no)
		(fp_rect
			(start -0.4318 0.9525)
			(end 0.4318 -0.9525)
			(stroke
				(width 0)
				(type default)
			)
			(fill no)
			(layer "F.CrtYd")
		)
		(fp_poly
			(pts
				(xy -0.4318 0.9525) (xy 0.4318 0.9525) (xy 0.4318 -0.9525) (xy -0.4318 -0.9525)
			)
			(stroke
				(width 0)
				(type default)
			)
			(fill no)
			(layer "F.Fab")
		)
		(pad "1" smd custom
			(at 0 -0.4445)
			(size 0.1524 0.1524)
			(layers "F.Cu" "F.Mask" "F.Paste")
			(net "VDDA_4")
			(options
				(clearance outline)
				(anchor circle)
			)
			(primitives
				(gr_poly
					(pts
						(arc
							(start 0.3048 -0.2032)
							(mid 0.275042 -0.275042)
							(end 0.2032 -0.3048)
						)
						(arc
							(start -0.2032 -0.3048)
							(mid -0.275042 -0.275042)
							(end -0.3048 -0.2032)
						)
						(arc
							(start -0.3048 0.2032)
							(mid -0.275042 0.275042)
							(end -0.2032 0.3048)
						)
						(arc
							(start 0.2032 0.3048)
							(mid 0.275042 0.275042)
							(end 0.3048 0.2032)
						)
					)
					(width 0)
					(fill yes)
				)
			)
		)
		(pad "2" smd custom
			(at 0 0.4445)
			(size 0.1524 0.1524)
			(layers "F.Cu" "F.Mask" "F.Paste")
			(net "GND")
			(options
				(clearance outline)
				(anchor circle)
			)
			(primitives
				(gr_poly
					(pts
						(arc
							(start 0.3048 -0.2032)
							(mid 0.275042 -0.275042)
							(end 0.2032 -0.3048)
						)
						(arc
							(start -0.2032 -0.3048)
							(mid -0.275042 -0.275042)
							(end -0.3048 -0.2032)
						)
						(arc
							(start -0.3048 0.2032)
							(mid -0.275042 0.275042)
							(end -0.2032 0.3048)
						)
						(arc
							(start 0.2032 0.3048)
							(mid 0.275042 0.275042)
							(end 0.3048 0.2032)
						)
					)
					(width 0)
					(fill yes)
				)
			)
		)
	)
	(footprint ""
		(layer "F.Cu")
		(at 30.099 -499.0084 180)
		(property "Reference" "PC1207"
			(at 0 0 180)
			(layer "F.SilkS")
			(hide yes)
			(effects
				(font
					(size 1.27 1.27)
				)
			)
		)
		(property "Value" "SCD1U50V3KX-GP"
			(at 0 -2.8194 180)
			(unlocked yes)
			(layer "F.Fab")
			(hide yes)
			(effects
				(font
					(size 1.016 1.016)
					(thickness 0.1524)
				)
			)
		)
		(property "Device Type" "C603H36"
			(at 0 -4.3434 180)
			(unlocked yes)
			(layer "F.Fab")
			(hide yes)
			(effects
				(font
					(size 1.016 1.016)
					(thickness 0.1524)
				)
			)
		)
		(duplicate_pad_numbers_are_jumpers no)
		(fp_line
			(start 0.508 0)
			(end -0.508 0)
			(stroke
				(width 0.2032)
				(type default)
			)
			(layer "F.SilkS")
		)
		(fp_rect
			(start -0.5842 1.3335)
			(end 0.5842 -1.3335)
			(stroke
				(width 0)
				(type default)
			)
			(fill no)
			(layer "F.CrtYd")
		)
		(fp_rect
			(start -0.5842 1.3335)
			(end 0.5842 -1.3335)
			(stroke
				(width 0)
				(type default)
			)
			(fill no)
			(layer "F.Fab")
		)
		(pad "1" smd custom
			(at 0 -0.762 180)
			(size 0.2159 0.2159)
			(layers "F.Cu" "F.Mask" "F.Paste")
			(net "P12V_SSD5")
			(options
				(clearance outline)
				(anchor circle)
			)
			(primitives
				(gr_poly
					(pts
						(arc
							(start -0.3302 -0.4318)
							(mid -0.402042 -0.402042)
							(end -0.4318 -0.3302)
						)
						(arc
							(start -0.4318 0.3302)
							(mid -0.402042 0.402042)
							(end -0.3302 0.4318)
						)
						(arc
							(start 0.3302 0.4318)
							(mid 0.402042 0.402042)
							(end 0.4318 0.3302)
						)
						(arc
							(start 0.4318 -0.3302)
							(mid 0.402042 -0.402042)
							(end 0.3302 -0.4318)
						)
					)
					(width 0)
					(fill yes)
				)
			)
		)
		(pad "2" smd custom
			(at 0 0.762 180)
			(size 0.2159 0.2159)
			(layers "F.Cu" "F.Mask" "F.Paste")
			(net "GND")
			(options
				(clearance outline)
				(anchor circle)
			)
			(primitives
				(gr_poly
					(pts
						(arc
							(start -0.3302 -0.4318)
							(mid -0.402042 -0.402042)
							(end -0.4318 -0.3302)
						)
						(arc
							(start -0.4318 0.3302)
							(mid -0.402042 0.402042)
							(end -0.3302 0.4318)
						)
						(arc
							(start 0.3302 0.4318)
							(mid 0.402042 0.402042)
							(end 0.4318 0.3302)
						)
						(arc
							(start 0.4318 -0.3302)
							(mid 0.402042 -0.402042)
							(end 0.3302 -0.4318)
						)
					)
					(width 0)
					(fill yes)
				)
			)
		)
	)
)
